(kicad_pcb
	(version 20260206)
	(generator "pcbnew")
	(generator_version "10.0")
	(general
		(thickness 1.6)
		(legacy_teardrops no)
	)
	(paper "A4")
	(title_block
		(title "timecard-production-celestica-r4006 — R4006-B0001-02_R01.brd")
		(comment 1 "Time Appliance Project (Time Card) / footprints 413-417 of 1113")
	)
	(layers
		(0 "F.Cu" signal "TOP")
		(4 "In1.Cu" signal "L02_GND1")
		(6 "In2.Cu" signal "L03_SIG1")
		(8 "In3.Cu" signal "L04_GND2")
		(10 "In4.Cu" signal "L05_VCC1")
		(12 "In5.Cu" signal "L06_VCC2")
		(14 "In6.Cu" signal "L07_GND3")
		(16 "In7.Cu" signal "L08_SIG2")
		(18 "In8.Cu" signal "L09_GND4")
		(2 "B.Cu" signal "BOTTOM")
		(9 "F.Adhes" user "F.Adhesive")
		(11 "B.Adhes" user "B.Adhesive")
		(13 "F.Paste" user "Package Geometry/Pastemask Top")
		(15 "B.Paste" user "Package Geometry/Pastemask Bottom")
		(5 "F.SilkS" user "Ref Des/Silkscreen Top")
		(7 "B.SilkS" user "Ref Des/Silkscreen Bottom")
		(1 "F.Mask" user "Board Geometry/Soldermask Top")
		(3 "B.Mask" user "Board Geometry/Soldermask Bottom")
		(17 "Dwgs.User" user "User.Drawings")
		(19 "Cmts.User" user "User.Comments")
		(21 "Eco1.User" user "User.Eco1")
		(23 "Eco2.User" user "User.Eco2")
		(25 "Edge.Cuts" user "Board Geometry/Outline")
		(27 "Margin" user)
		(31 "F.CrtYd" user "Package Geometry/Place Bound Top")
		(29 "B.CrtYd" user "Package Geometry/Place Bound Bottom")
		(35 "F.Fab" user "Ref Des/Assembly Top")
		(33 "B.Fab" user "Ref Des/Assembly Bottom")
	)
	(footprint ""
		(layer "F.Cu")
		(at 19.468338 -46.736 180)
		(property "Reference" "R424"
			(at -3.518662 -0.03937 0)
			(unlocked yes)
			(layer "F.SilkS")
			(effects
				(font
					(size 0.7874 0.5842)
					(thickness 0.1524)
				)
			)
		)
		(property "Value" "VAL*"
			(at 0.02032 2.13233 180)
			(unlocked yes)
			(layer "F.Fab")
			(hide yes)
			(effects
				(font
					(size 0.7874 0.5842)
					(thickness 0.1524)
				)
			)
		)
		(property "Device Type" "RESISTOR-G155-11000-01,100OHM,A"
			(at 0.008382 1.210564 180)
			(unlocked yes)
			(layer "F.Fab")
			(hide yes)
			(effects
				(font
					(size 0.7874 0.5842)
					(thickness 0.1524)
				)
			)
		)
		(property "User Part Number" "PARTNUM*"
			(at 0.02032 4.024884 180)
			(unlocked yes)
			(layer "Cmts.User")
			(hide yes)
			(effects
				(font
					(size 0.7874 0.5842)
					(thickness 0.1524)
				)
			)
		)
		(property "Tolerance" "TOL*"
			(at 0.044704 3.05435 180)
			(unlocked yes)
			(layer "Cmts.User")
			(hide yes)
			(effects
				(font
					(size 0.7874 0.5842)
					(thickness 0.1524)
				)
			)
		)
		(duplicate_pad_numbers_are_jumpers no)
		(fp_line
			(start 1.143 0.5588)
			(end 1.143 -0.5588)
			(stroke
				(width 0.1)
				(type default)
			)
			(layer "F.SilkS")
		)
		(fp_line
			(start 1.143 -0.5588)
			(end -1.143 -0.5588)
			(stroke
				(width 0.1)
				(type default)
			)
			(layer "F.SilkS")
		)
		(fp_line
			(start -1.143 0.5588)
			(end 1.143 0.5588)
			(stroke
				(width 0.1)
				(type default)
			)
			(layer "F.SilkS")
		)
		(fp_line
			(start -1.143 -0.5588)
			(end -1.143 0.5588)
			(stroke
				(width 0.1)
				(type default)
			)
			(layer "F.SilkS")
		)
		(fp_poly
			(pts
				(xy -1.143 0.5588) (xy 1.143 0.5588) (xy 1.143 -0.5588) (xy -1.143 -0.5588)
			)
			(stroke
				(width 0)
				(type default)
			)
			(fill no)
			(layer "F.CrtYd")
		)
		(fp_line
			(start 0.508 0.3048)
			(end 0.508 -0.3048)
			(stroke
				(width 0.1)
				(type default)
			)
			(layer "F.Fab")
		)
		(fp_line
			(start 0.508 -0.3048)
			(end -0.508 -0.3048)
			(stroke
				(width 0.1)
				(type default)
			)
			(layer "F.Fab")
		)
		(fp_line
			(start -0.508 0.3048)
			(end 0.508 0.3048)
			(stroke
				(width 0.1)
				(type default)
			)
			(layer "F.Fab")
		)
		(fp_line
			(start -0.508 -0.3048)
			(end -0.508 0.3048)
			(stroke
				(width 0.1)
				(type default)
			)
			(layer "F.Fab")
		)
		(pad "1" smd rect
			(at -0.5334 0 180)
			(size 0.7112 0.6096)
			(layers "F.Cu" "F.Mask" "F.Paste")
			(net "FPGA_OUT_SMA4_LED_RED_N")
		)
		(pad "2" smd rect
			(at 0.5334 0 180)
			(size 0.7112 0.6096)
			(layers "F.Cu" "F.Mask" "F.Paste")
			(net "UNNAMED_14_LED4PV14_I268_3")
		)
		(zone
			(layer "F.Cu")
			(hatch none 0.5)
			(connect_pads
				(clearance 0)
			)
			(min_thickness 0.25)
			(keepout
				(tracks allowed)
				(vias not_allowed)
				(pads allowed)
				(copperpour not_allowed)
				(footprints allowed)
			)
			(placement
				(enabled no)
				(sheetname "")
			)
			(fill
				(thermal_gap 0.5)
				(thermal_bridge_width 0.5)
				(island_removal_mode 0)
			)
			(polygon
				(pts
					(xy 19.544538 -47.0408) (xy 19.392138 -47.0408) (xy 19.392138 -46.4312) (xy 19.544538 -46.4312)
				)
			)
		)
		(zone
			(layer "F.Cu")
			(hatch none 0.5)
			(connect_pads
				(clearance 0)
			)
			(min_thickness 0.25)
			(keepout
				(tracks not_allowed)
				(vias allowed)
				(pads allowed)
				(copperpour not_allowed)
				(footprints allowed)
			)
			(placement
				(enabled no)
				(sheetname "")
			)
			(fill
				(thermal_gap 0.5)
				(thermal_bridge_width 0.5)
				(island_removal_mode 0)
			)
			(polygon
				(pts
					(xy 19.544538 -47.0408) (xy 19.392138 -47.0408) (xy 19.392138 -46.4312) (xy 19.544538 -46.4312)
				)
			)
		)
	)
	(footprint ""
		(layer "F.Cu")
		(at 115.443 -74.803)
		(property "Reference" "C236"
			(at 3.302 0.42037 0)
			(unlocked yes)
			(layer "F.SilkS")
			(effects
				(font
					(size 0.7874 0.5842)
					(thickness 0.1524)
				)
			)
		)
		(property "Value" "VAL*"
			(at 0.0762 2.067306 0)
			(unlocked yes)
			(layer "F.Fab")
			(hide yes)
			(effects
				(font
					(size 0.7874 0.5842)
					(thickness 0.1524)
				)
			)
		)
		(property "Device Type" "CAPACITOR-G105-0B104-EK,0.1UF,A"
			(at 0.0508 1.127506 0)
			(unlocked yes)
			(layer "F.Fab")
			(hide yes)
			(effects
				(font
					(size 0.7874 0.5842)
					(thickness 0.1524)
				)
			)
		)
		(property "User Part Number" "PARTNUM*"
			(at 0.1016 4.023106 0)
			(unlocked yes)
			(layer "Cmts.User")
			(hide yes)
			(effects
				(font
					(size 0.7874 0.5842)
					(thickness 0.1524)
				)
			)
		)
		(property "Tolerance" "TOL*"
			(at 0.0762 3.032506 0)
			(unlocked yes)
			(layer "Cmts.User")
			(hide yes)
			(effects
				(font
					(size 0.7874 0.5842)
					(thickness 0.1524)
				)
			)
		)
		(duplicate_pad_numbers_are_jumpers no)
		(fp_line
			(start -1.143 -0.5588)
			(end -1.143 0.5588)
			(stroke
				(width 0.1)
				(type default)
			)
			(layer "F.SilkS")
		)
		(fp_line
			(start -1.143 0.5588)
			(end 1.143 0.5588)
			(stroke
				(width 0.1)
				(type default)
			)
			(layer "F.SilkS")
		)
		(fp_line
			(start 1.143 -0.5588)
			(end -1.143 -0.5588)
			(stroke
				(width 0.1)
				(type default)
			)
			(layer "F.SilkS")
		)
		(fp_line
			(start 1.143 0.5588)
			(end 1.143 -0.5588)
			(stroke
				(width 0.1)
				(type default)
			)
			(layer "F.SilkS")
		)
		(fp_rect
			(start -1.143 0.5588)
			(end 1.143 -0.5588)
			(stroke
				(width 0)
				(type default)
			)
			(fill no)
			(layer "F.CrtYd")
		)
		(fp_line
			(start -0.508 -0.3048)
			(end -0.508 0.3048)
			(stroke
				(width 0.1)
				(type default)
			)
			(layer "F.Fab")
		)
		(fp_line
			(start -0.508 0.3048)
			(end 0.508 0.3048)
			(stroke
				(width 0.1)
				(type default)
			)
			(layer "F.Fab")
		)
		(fp_line
			(start 0.508 -0.3048)
			(end -0.508 -0.3048)
			(stroke
				(width 0.1)
				(type default)
			)
			(layer "F.Fab")
		)
		(fp_line
			(start 0.508 0.3048)
			(end 0.508 -0.3048)
			(stroke
				(width 0.1)
				(type default)
			)
			(layer "F.Fab")
		)
		(pad "1" smd rect
			(at -0.5334 0)
			(size 0.7112 0.6096)
			(layers "F.Cu" "F.Mask" "F.Paste")
			(net "XP3R3V_FPGA_SR")
		)
		(pad "2" smd rect
			(at 0.5334 0)
			(size 0.7112 0.6096)
			(layers "F.Cu" "F.Mask" "F.Paste")
			(net "SG")
		)
		(zone
			(layer "F.Cu")
			(hatch none 0.5)
			(connect_pads
				(clearance 0)
			)
			(min_thickness 0.25)
			(keepout
				(tracks allowed)
				(vias not_allowed)
				(pads allowed)
				(copperpour not_allowed)
				(footprints allowed)
			)
			(placement
				(enabled no)
				(sheetname "")
			)
			(fill
				(thermal_gap 0.5)
				(thermal_bridge_width 0.5)
				(island_removal_mode 0)
			)
			(polygon
				(pts
					(xy 115.3668 -74.4982) (xy 115.5192 -74.4982) (xy 115.5192 -75.1078) (xy 115.3668 -75.1078)
				)
			)
		)
	)
	(footprint ""
		(layer "F.Cu")
		(at 38.862 -76.835 -90)
		(property "Reference" "R490"
			(at 0.889 3.77063 90)
			(unlocked yes)
			(layer "F.SilkS")
			(effects
				(font
					(size 0.7874 0.5842)
					(thickness 0.1524)
				)
			)
		)
		(property "Value" "VAL*"
			(at 0.02032 2.13233 270)
			(unlocked yes)
			(layer "F.Fab")
			(hide yes)
			(effects
				(font
					(size 0.7874 0.5842)
					(thickness 0.1524)
				)
			)
		)
		(property "Tolerance" "TOL*"
			(at 0.044704 3.05435 270)
			(unlocked yes)
			(layer "Cmts.User")
			(hide yes)
			(effects
				(font
					(size 0.7874 0.5842)
					(thickness 0.1524)
				)
			)
		)
		(property "User Part Number" "PARTNUM*"
			(at 0.02032 4.024884 270)
			(unlocked yes)
			(layer "Cmts.User")
			(hide yes)
			(effects
				(font
					(size 0.7874 0.5842)
					(thickness 0.1524)
				)
			)
		)
		(property "Device Type" "RESISTOR-G155-11002-01,10KOHM,A"
			(at 0.008382 1.210564 270)
			(unlocked yes)
			(layer "F.Fab")
			(hide yes)
			(effects
				(font
					(size 0.7874 0.5842)
					(thickness 0.1524)
				)
			)
		)
		(duplicate_pad_numbers_are_jumpers no)
		(fp_line
			(start -1.143 0.5588)
			(end 1.143 0.5588)
			(stroke
				(width 0.1)
				(type default)
			)
			(layer "F.SilkS")
		)
		(fp_line
			(start 1.143 0.5588)
			(end 1.143 -0.5588)
			(stroke
				(width 0.1)
				(type default)
			)
			(layer "F.SilkS")
		)
		(fp_line
			(start -1.143 -0.5588)
			(end -1.143 0.5588)
			(stroke
				(width 0.1)
				(type default)
			)
			(layer "F.SilkS")
		)
		(fp_line
			(start 1.143 -0.5588)
			(end -1.143 -0.5588)
			(stroke
				(width 0.1)
				(type default)
			)
			(layer "F.SilkS")
		)
		(fp_poly
			(pts
				(xy -1.143 0.5588) (xy 1.143 0.5588) (xy 1.143 -0.5588) (xy -1.143 -0.5588)
			)
			(stroke
				(width 0)
				(type default)
			)
			(fill no)
			(layer "F.CrtYd")
		)
		(fp_line
			(start -0.508 0.3048)
			(end 0.508 0.3048)
			(stroke
				(width 0.1)
				(type default)
			)
			(layer "F.Fab")
		)
		(fp_line
			(start 0.508 0.3048)
			(end 0.508 -0.3048)
			(stroke
				(width 0.1)
				(type default)
			)
			(layer "F.Fab")
		)
		(fp_line
			(start -0.508 -0.3048)
			(end -0.508 0.3048)
			(stroke
				(width 0.1)
				(type default)
			)
			(layer "F.Fab")
		)
		(fp_line
			(start 0.508 -0.3048)
			(end -0.508 -0.3048)
			(stroke
				(width 0.1)
				(type default)
			)
			(layer "F.Fab")
		)
		(pad "1" smd rect
			(at -0.5334 0 270)
			(size 0.7112 0.6096)
			(layers "F.Cu" "F.Mask" "F.Paste")
			(net "XP3R3V_FT4232")
		)
		(pad "2" smd rect
			(at 0.5334 0 270)
			(size 0.7112 0.6096)
			(layers "F.Cu" "F.Mask" "F.Paste")
			(net "UNNAMED_525_ISL80101IRAJZDFN10_")
		)
		(zone
			(layer "F.Cu")
			(hatch none 0.5)
			(connect_pads
				(clearance 0)
			)
			(min_thickness 0.25)
			(keepout
				(tracks allowed)
				(vias not_allowed)
				(pads allowed)
				(copperpour not_allowed)
				(footprints allowed)
			)
			(placement
				(enabled no)
				(sheetname "")
			)
			(fill
				(thermal_gap 0.5)
				(thermal_bridge_width 0.5)
				(island_removal_mode 0)
			)
			(polygon
				(pts
					(xy 38.5572 -76.9112) (xy 38.5572 -76.7588) (xy 39.1668 -76.7588) (xy 39.1668 -76.9112)
				)
			)
		)
		(zone
			(layer "F.Cu")
			(hatch none 0.5)
			(connect_pads
				(clearance 0)
			)
			(min_thickness 0.25)
			(keepout
				(tracks not_allowed)
				(vias allowed)
				(pads allowed)
				(copperpour not_allowed)
				(footprints allowed)
			)
			(placement
				(enabled no)
				(sheetname "")
			)
			(fill
				(thermal_gap 0.5)
				(thermal_bridge_width 0.5)
				(island_removal_mode 0)
			)
			(polygon
				(pts
					(xy 38.5572 -76.9112) (xy 38.5572 -76.7588) (xy 39.1668 -76.7588) (xy 39.1668 -76.9112)
				)
			)
		)
	)
	(footprint ""
		(layer "F.Cu")
		(at 152.883108 -49.01311 -90)
		(property "Reference" "R299"
			(at 0.11811 -2.858262 90)
			(unlocked yes)
			(layer "F.SilkS")
			(effects
				(font
					(size 0.7874 0.5842)
					(thickness 0.1524)
				)
			)
		)
		(property "Value" "VAL*"
			(at 0.02032 2.13233 270)
			(unlocked yes)
			(layer "F.Fab")
			(hide yes)
			(effects
				(font
					(size 0.7874 0.5842)
					(thickness 0.1524)
				)
			)
		)
		(property "Device Type" "RESISTOR-G155-133R0-01,33OHM,1%"
			(at 0.008382 1.210564 270)
			(unlocked yes)
			(layer "F.Fab")
			(hide yes)
			(effects
				(font
					(size 0.7874 0.5842)
					(thickness 0.1524)
				)
			)
		)
		(property "User Part Number" "PARTNUM*"
			(at 0.02032 4.024884 270)
			(unlocked yes)
			(layer "Cmts.User")
			(hide yes)
			(effects
				(font
					(size 0.7874 0.5842)
					(thickness 0.1524)
				)
			)
		)
		(property "Tolerance" "TOL*"
			(at 0.044704 3.05435 270)
			(unlocked yes)
			(layer "Cmts.User")
			(hide yes)
			(effects
				(font
					(size 0.7874 0.5842)
					(thickness 0.1524)
				)
			)
		)
		(duplicate_pad_numbers_are_jumpers no)
		(fp_line
			(start -1.143 0.5588)
			(end 1.143 0.5588)
			(stroke
				(width 0.1)
				(type default)
			)
			(layer "F.SilkS")
		)
		(fp_line
			(start 1.143 0.5588)
			(end 1.143 -0.5588)
			(stroke
				(width 0.1)
				(type default)
			)
			(layer "F.SilkS")
		)
		(fp_line
			(start -1.143 -0.5588)
			(end -1.143 0.5588)
			(stroke
				(width 0.1)
				(type default)
			)
			(layer "F.SilkS")
		)
		(fp_line
			(start 1.143 -0.5588)
			(end -1.143 -0.5588)
			(stroke
				(width 0.1)
				(type default)
			)
			(layer "F.SilkS")
		)
		(fp_rect
			(start -1.143 -0.5588)
			(end 1.143 0.5588)
			(stroke
				(width 0)
				(type default)
			)
			(fill no)
			(layer "F.CrtYd")
		)
		(fp_line
			(start -0.508 0.3048)
			(end 0.508 0.3048)
			(stroke
				(width 0.1)
				(type default)
			)
			(layer "F.Fab")
		)
		(fp_line
			(start 0.508 0.3048)
			(end 0.508 -0.3048)
			(stroke
				(width 0.1)
				(type default)
			)
			(layer "F.Fab")
		)
		(fp_line
			(start -0.508 -0.3048)
			(end -0.508 0.3048)
			(stroke
				(width 0.1)
				(type default)
			)
			(layer "F.Fab")
		)
		(fp_line
			(start 0.508 -0.3048)
			(end -0.508 -0.3048)
			(stroke
				(width 0.1)
				(type default)
			)
			(layer "F.Fab")
		)
		(pad "1" smd rect
			(at -0.5334 0 270)
			(size 0.7112 0.6096)
			(layers "F.Cu" "F.Mask" "F.Paste")
			(net "R_SHT3X_ALERT_N")
		)
		(pad "2" smd rect
			(at 0.5334 0 270)
			(size 0.7112 0.6096)
			(layers "F.Cu" "F.Mask" "F.Paste")
			(net "FPGA_IN_SHT3X_ALERT_N")
		)
		(zone
			(layer "F.Cu")
			(hatch none 0.5)
			(connect_pads
				(clearance 0)
			)
			(min_thickness 0.25)
			(keepout
				(tracks allowed)
				(vias not_allowed)
				(pads allowed)
				(copperpour not_allowed)
				(footprints allowed)
			)
			(placement
				(enabled no)
				(sheetname "")
			)
			(fill
				(thermal_gap 0.5)
				(thermal_bridge_width 0.5)
				(island_removal_mode 0)
			)
			(polygon
				(pts
					(xy 153.187908 -49.08931) (xy 152.578308 -49.08931) (xy 152.578308 -48.93691) (xy 153.187908 -48.93691)
				)
			)
		)
	)
	(footprint ""
		(layer "F.Cu")
		(at 118.11 -58.928 90)
		(property "Reference" "R362"
			(at -0.127 1.30937 90)
			(unlocked yes)
			(layer "F.SilkS")
			(effects
				(font
					(size 0.7874 0.5842)
					(thickness 0.1524)
				)
			)
		)
		(property "Value" "VAL*"
			(at 0.02032 2.13233 90)
			(unlocked yes)
			(layer "F.Fab")
			(hide yes)
			(effects
				(font
					(size 0.7874 0.5842)
					(thickness 0.1524)
				)
			)
		)
		(property "Tolerance" "TOL*"
			(at 0.044704 3.05435 90)
			(unlocked yes)
			(layer "Cmts.User")
			(hide yes)
			(effects
				(font
					(size 0.7874 0.5842)
					(thickness 0.1524)
				)
			)
		)
		(property "User Part Number" "PARTNUM*"
			(at 0.02032 4.024884 90)
			(unlocked yes)
			(layer "Cmts.User")
			(hide yes)
			(effects
				(font
					(size 0.7874 0.5842)
					(thickness 0.1524)
				)
			)
		)
		(property "Device Type" "RESISTOR-G155-133R0-01,33OHM,1%"
			(at 0.008382 1.210564 90)
			(unlocked yes)
			(layer "F.Fab")
			(hide yes)
			(effects
				(font
					(size 0.7874 0.5842)
					(thickness 0.1524)
				)
			)
		)
		(duplicate_pad_numbers_are_jumpers no)
		(fp_line
			(start 1.143 -0.5588)
			(end -1.143 -0.5588)
			(stroke
				(width 0.1)
				(type default)
			)
			(layer "F.SilkS")
		)
		(fp_line
			(start -1.143 -0.5588)
			(end -1.143 0.5588)
			(stroke
				(width 0.1)
				(type default)
			)
			(layer "F.SilkS")
		)
		(fp_line
			(start 1.143 0.5588)
			(end 1.143 -0.5588)
			(stroke
				(width 0.1)
				(type default)
			)
			(layer "F.SilkS")
		)
		(fp_line
			(start -1.143 0.5588)
			(end 1.143 0.5588)
			(stroke
				(width 0.1)
				(type default)
			)
			(layer "F.SilkS")
		)
		(fp_poly
			(pts
				(xy -1.143 0.5588) (xy 1.143 0.5588) (xy 1.143 -0.5588) (xy -1.143 -0.5588)
			)
			(stroke
				(width 0)
				(type default)
			)
			(fill no)
			(layer "F.CrtYd")
		)
		(fp_line
			(start 0.508 -0.3048)
			(end -0.508 -0.3048)
			(stroke
				(width 0.1)
				(type default)
			)
			(layer "F.Fab")
		)
		(fp_line
			(start -0.508 -0.3048)
			(end -0.508 0.3048)
			(stroke
				(width 0.1)
				(type default)
			)
			(layer "F.Fab")
		)
		(fp_line
			(start 0.508 0.3048)
			(end 0.508 -0.3048)
			(stroke
				(width 0.1)
				(type default)
			)
			(layer "F.Fab")
		)
		(fp_line
			(start -0.508 0.3048)
			(end 0.508 0.3048)
			(stroke
				(width 0.1)
				(type default)
			)
			(layer "F.Fab")
		)
		(pad "1" smd rect
			(at -0.5334 0 90)
			(size 0.7112 0.6096)
			(layers "F.Cu" "F.Mask" "F.Paste")
			(net "FPGA_FCS_B")
		)
		(pad "2" smd rect
			(at 0.5334 0 90)
			(size 0.7112 0.6096)
			(layers "F.Cu" "F.Mask" "F.Paste")
			(net "FPGA_FLASH_CS_N")
		)
		(zone
			(layer "F.Cu")
			(hatch none 0.5)
			(connect_pads
				(clearance 0)
			)
			(min_thickness 0.25)
			(keepout
				(tracks not_allowed)
				(vias allowed)
				(pads allowed)
				(copperpour not_allowed)
				(footprints allowed)
			)
			(placement
				(enabled no)
				(sheetname "")
			)
			(fill
				(thermal_gap 0.5)
				(thermal_bridge_width 0.5)
				(island_removal_mode 0)
			)
			(polygon
				(pts
					(xy 118.4148 -58.8518) (xy 118.4148 -59.0042) (xy 117.8052 -59.0042) (xy 117.8052 -58.8518)
				)
			)
		)
		(zone
			(layer "F.Cu")
			(hatch none 0.5)
			(connect_pads
				(clearance 0)
			)
			(min_thickness 0.25)
			(keepout
				(tracks allowed)
				(vias not_allowed)
				(pads allowed)
				(copperpour not_allowed)
				(footprints allowed)
			)
			(placement
				(enabled no)
				(sheetname "")
			)
			(fill
				(thermal_gap 0.5)
				(thermal_bridge_width 0.5)
				(island_removal_mode 0)
			)
			(polygon
				(pts
					(xy 118.4148 -58.8518) (xy 118.4148 -59.0042) (xy 117.8052 -59.0042) (xy 117.8052 -58.8518)
				)
			)
		)
	)
)
